# S9S_MB_2U (Grand Teton) — schematic netlist excerpt (pin names and nets, part order shuffled) for the footprints in the layout excerpt that follows; sources: Cadence DE-HDL packaged netlist, KiCad conversion of 03242023_DA0F0TMBIJ0_F0T_Motherboard_J_brd_V01_OCP.brd

R2526  Q_RES  0 5% CHIP  pkg 0402LF  page 190 : A = FM_M2_SSD_0_PEDET ; B = FM_M2_SSD0_E7_PEDET
R4060  Q_RES  0 5% CHIP  pkg 0402LF  page 162 : A = HP_LVC3_OCP_V3_2_EN ; B = P3V3_OCP_EN_2_R

(kicad_pcb
	(version 20260206)
	(generator "pcbnew")
	(generator_version "10.0")
	(general
		(thickness 1.6)
		(legacy_teardrops no)
	)
	(paper "A4")
	(title_block
		(title "03242023_DA0F0TMBIJ0_F0T_Motherboard_J_brd_V01_OCP.brd")
		(comment 1 "Grand Teton / footprints 2357-2358 of 6105")
	)
	(layers
		(0 "F.Cu" signal "TOP")
		(4 "In1.Cu" signal "GND")
		(6 "In2.Cu" signal "IN1")
		(8 "In3.Cu" signal "GND1")
		(10 "In4.Cu" signal "IN2")
		(12 "In5.Cu" signal "GND2")
		(14 "In6.Cu" signal "IN3")
		(16 "In7.Cu" signal "GND3")
		(18 "In8.Cu" signal "VCC")
		(20 "In9.Cu" signal "VCC1")
		(22 "In10.Cu" signal "GND4")
		(24 "In11.Cu" signal "IN4")
		(26 "In12.Cu" signal "GND5")
		(28 "In13.Cu" signal "IN5")
		(30 "In14.Cu" signal "GND6")
		(32 "In15.Cu" signal "IN6")
		(34 "In16.Cu" signal "GND7")
		(2 "B.Cu" signal "BOTTOM")
		(9 "F.Adhes" user "F.Adhesive")
		(11 "B.Adhes" user "B.Adhesive")
		(13 "F.Paste" user "Package Geometry/Pastemask Top")
		(15 "B.Paste" user "Package Geometry/Pastemask Bottom")
		(5 "F.SilkS" user "Ref Des/Silkscreen Top")
		(7 "B.SilkS" user "Ref Des/Silkscreen Bottom")
		(1 "F.Mask" user "Board Geometry/Soldermask Top")
		(3 "B.Mask" user "Board Geometry/Soldermask Bottom")
		(17 "Dwgs.User" user "User.Drawings")
		(19 "Cmts.User" user "User.Comments")
		(21 "Eco1.User" user "User.Eco1")
		(23 "Eco2.User" user "User.Eco2")
		(25 "Edge.Cuts" user "Board Geometry/Outline")
		(27 "Margin" user)
		(31 "F.CrtYd" user "Package Geometry/Place Bound Top")
		(29 "B.CrtYd" user "Package Geometry/Place Bound Bottom")
		(35 "F.Fab" user "Ref Des/Assembly Top")
		(33 "B.Fab" user "Ref Des/Assembly Bottom")
	)
	(footprint ""
		(layer "F.Cu")
		(at 58.93308 -39.148004)
		(property "Reference" "R4060"
			(at 0 0 0)
			(layer "F.SilkS")
			(hide yes)
			(effects
				(font
					(size 1.27 1.27)
				)
			)
		)
		(property "Value" ""
			(at 0 0 0)
			(layer "F.Fab")
			(effects
				(font
					(size 1.27 1.27)
				)
			)
		)
		(duplicate_pad_numbers_are_jumpers no)
		(fp_line
			(start -0.7874 -0.4064)
			(end 0.7874 -0.4064)
			(stroke
				(width 0.1524)
				(type default)
			)
			(layer "F.SilkS")
		)
		(fp_line
			(start -0.7874 0.4064)
			(end -0.7874 -0.4064)
			(stroke
				(width 0.1524)
				(type default)
			)
			(layer "F.SilkS")
		)
		(fp_line
			(start 0.7874 -0.4064)
			(end 0.7874 0.4064)
			(stroke
				(width 0.1524)
				(type default)
			)
			(layer "F.SilkS")
		)
		(fp_line
			(start 0.7874 0.4064)
			(end -0.7874 0.4064)
			(stroke
				(width 0.1524)
				(type default)
			)
			(layer "F.SilkS")
		)
		(fp_line
			(start -0.67945 -0.305054)
			(end -0.12065 -0.305054)
			(stroke
				(width 0.1)
				(type default)
			)
			(layer "F.Fab")
		)
		(fp_line
			(start -0.67945 0.3048)
			(end -0.67945 -0.305054)
			(stroke
				(width 0.1)
				(type default)
			)
			(layer "F.Fab")
		)
		(fp_line
			(start -0.12065 -0.305054)
			(end -0.12065 -0.2794)
			(stroke
				(width 0.1)
				(type default)
			)
			(layer "F.Fab")
		)
		(fp_line
			(start -0.12065 -0.2794)
			(end 0.12065 -0.2794)
			(stroke
				(width 0.1)
				(type default)
			)
			(layer "F.Fab")
		)
		(fp_line
			(start -0.12065 0.2794)
			(end -0.12065 0.3048)
			(stroke
				(width 0.1)
				(type default)
			)
			(layer "F.Fab")
		)
		(fp_line
			(start -0.12065 0.3048)
			(end -0.67945 0.3048)
			(stroke
				(width 0.1)
				(type default)
			)
			(layer "F.Fab")
		)
		(fp_line
			(start 0.120396 0.2794)
			(end -0.12065 0.2794)
			(stroke
				(width 0.1)
				(type default)
			)
			(layer "F.Fab")
		)
		(fp_line
			(start 0.120396 0.3048)
			(end 0.120396 0.2794)
			(stroke
				(width 0.1)
				(type default)
			)
			(layer "F.Fab")
		)
		(fp_line
			(start 0.12065 -0.3048)
			(end 0.67945 -0.3048)
			(stroke
				(width 0.1)
				(type default)
			)
			(layer "F.Fab")
		)
		(fp_line
			(start 0.12065 -0.2794)
			(end 0.12065 -0.3048)
			(stroke
				(width 0.1)
				(type default)
			)
			(layer "F.Fab")
		)
		(fp_line
			(start 0.67945 -0.3048)
			(end 0.67945 0.3048)
			(stroke
				(width 0.1)
				(type default)
			)
			(layer "F.Fab")
		)
		(fp_line
			(start 0.67945 0.3048)
			(end 0.120396 0.3048)
			(stroke
				(width 0.1)
				(type default)
			)
			(layer "F.Fab")
		)
		(pad "1" smd circle
			(at -0.40005 0)
			(size 0 0)
			(layers "F.Cu" "F.Mask" "F.Paste")
			(net "HP_LVC3_OCP_V3_2_EN")
		)
		(pad "2" smd circle
			(at 0.40005 0)
			(size 0 0)
			(layers "F.Cu" "F.Mask" "F.Paste")
			(net "P3V3_OCP_EN_2_R")
		)
	)
	(footprint ""
		(layer "F.Cu")
		(at 180.77688 -41.112948)
		(property "Reference" "R2526"
			(at 0 0 0)
			(layer "F.SilkS")
			(hide yes)
			(effects
				(font
					(size 1.27 1.27)
				)
			)
		)
		(property "Value" ""
			(at 0 0 0)
			(layer "F.Fab")
			(effects
				(font
					(size 1.27 1.27)
				)
			)
		)
		(duplicate_pad_numbers_are_jumpers no)
		(fp_line
			(start -0.7874 -0.4064)
			(end 0.7874 -0.4064)
			(stroke
				(width 0.1524)
				(type default)
			)
			(layer "F.SilkS")
		)
		(fp_line
			(start -0.7874 0.4064)
			(end -0.7874 -0.4064)
			(stroke
				(width 0.1524)
				(type default)
			)
			(layer "F.SilkS")
		)
		(fp_line
			(start 0.7874 -0.4064)
			(end 0.7874 0.4064)
			(stroke
				(width 0.1524)
				(type default)
			)
			(layer "F.SilkS")
		)
		(fp_line
			(start 0.7874 0.4064)
			(end -0.7874 0.4064)
			(stroke
				(width 0.1524)
				(type default)
			)
			(layer "F.SilkS")
		)
		(fp_line
			(start -0.67945 -0.305054)
			(end -0.12065 -0.305054)
			(stroke
				(width 0.1)
				(type default)
			)
			(layer "F.Fab")
		)
		(fp_line
			(start -0.67945 0.3048)
			(end -0.67945 -0.305054)
			(stroke
				(width 0.1)
				(type default)
			)
			(layer "F.Fab")
		)
		(fp_line
			(start -0.12065 -0.305054)
			(end -0.12065 -0.2794)
			(stroke
				(width 0.1)
				(type default)
			)
			(layer "F.Fab")
		)
		(fp_line
			(start -0.12065 -0.2794)
			(end 0.12065 -0.2794)
			(stroke
				(width 0.1)
				(type default)
			)
			(layer "F.Fab")
		)
		(fp_line
			(start -0.12065 0.2794)
			(end -0.12065 0.3048)
			(stroke
				(width 0.1)
				(type default)
			)
			(layer "F.Fab")
		)
		(fp_line
			(start -0.12065 0.3048)
			(end -0.67945 0.3048)
			(stroke
				(width 0.1)
				(type default)
			)
			(layer "F.Fab")
		)
		(fp_line
			(start 0.120396 0.2794)
			(end -0.12065 0.2794)
			(stroke
				(width 0.1)
				(type default)
			)
			(layer "F.Fab")
		)
		(fp_line
			(start 0.120396 0.3048)
			(end 0.120396 0.2794)
			(stroke
				(width 0.1)
				(type default)
			)
			(layer "F.Fab")
		)
		(fp_line
			(start 0.12065 -0.3048)
			(end 0.67945 -0.3048)
			(stroke
				(width 0.1)
				(type default)
			)
			(layer "F.Fab")
		)
		(fp_line
			(start 0.12065 -0.2794)
			(end 0.12065 -0.3048)
			(stroke
				(width 0.1)
				(type default)
			)
			(layer "F.Fab")
		)
		(fp_line
			(start 0.67945 -0.3048)
			(end 0.67945 0.3048)
			(stroke
				(width 0.1)
				(type default)
			)
			(layer "F.Fab")
		)
		(fp_line
			(start 0.67945 0.3048)
			(end 0.120396 0.3048)
			(stroke
				(width 0.1)
				(type default)
			)
			(layer "F.Fab")
		)
		(pad "1" smd circle
			(at -0.40005 0)
			(size 0 0)
			(layers "F.Cu" "F.Mask" "F.Paste")
			(net "FM_M2_SSD_0_PEDET")
		)
		(pad "2" smd circle
			(at 0.40005 0)
			(size 0 0)
			(layers "F.Cu" "F.Mask" "F.Paste")
			(net "FM_M2_SSD0_E7_PEDET")
		)
	)
)
